FILE_TYPE = CONNECTIVITY;
{Allegro Design Entry HDL 17.2-2016 S081 (4005846) 1/11/2022}
"PAGE_NUMBER" = 110;
0"NC";
1"GND\g";
2"GND\g";
3"GND\g";
4"GND\g";
5"GND\g";
6"GND\g";
7"GND\g";
8"GND\g";
9"GND\g";
10"GND\g";
11"GND\g";
12"GND\g";
13"GND\g";
14"GND\g";
15"GND\g";
16"GND\g";
17"GND\g";
18"GND\g";
19"P3V3\g";
20"P3V3\g";
21"GND\g";
22"GND\g";
23"P3V3\g";
24"GND\g";
25"P3V3\g";
26"GND\g";
27"P3V3\g";
28"P3V3_9ZX_VDD_1\g";
29"SADR_0";
30"SADR_1";
31"P3V3\g";
32"P3V3_9ZX_VDD_0\g";
33"P3V3_9ZX_VDDA_1\g";
34"GND\g";
35"P3V3\g";
36"FM_CLK_BUFFER1_EN";
37"FM_CLK_BUFFER0_EN";
38"SMB_CPU0_2_XLTR_SCL";
39"SMB_CPU0_2_XLTR_SDA";
40"FM_CLK_BUFFER1_EN";
41"FM_CLK_BUFFER1_EN_R";
42"SMB_CLK_BUF1_SCL";
43"SMB_CLK_BUF1_SDA";
44"CLK_100M_CPU1_CLK13_DN";
45"SADR_1";
46"P3V3_9ZX_VDDA_1\g";
47"CLK_100M_CPU1_CLK13_DP";
48"P3V3_9ZX_VDD_1\g";
49"P3V3_9ZX_VDDA_0\g";
50"SMB_CPU0_2_XLTR_SCL";
51"SMB_CPU0_2_XLTR_SDA";
52"FM_CLK_BUFFER0_EN";
53"SMB_CLK_BUF0_SCL";
54"SMB_CLK_BUF0_SDA";
55"FM_CLK_BUFFER0_EN_R";
56"SADR_0";
57"P3V3_9ZX_VDDA_0\g";
58"CLK_100M_CPU0_CLK13_DN";
59"CLK_100M_CPU0_CLK13_DP";
60"P3V3_9ZX_VDD_0\g";
61"CLK_100M_SLOT2_1_R_DN";
62"CLK_100M_SLOT2_2_R_DN";
63"CLK_100M_SLOT2_2_R_DP";
64"CLK_100M_SLOT2_3_R_DP";
65"CLK_100M_SLOT2_3_R_DN";
66"FM_CLK_100M_SLOT2_2_OE_N";
67"FM_CLK_100M_SLOT2_3_OE_N";
68"FM_CLK_100M_SLOT2_1_OE_N";
69"FM_CLK_100M_SLOT2_0_OE_N";
70"GND\g";
71"CLK_100M_SLOT2_1_DN";
72"CLK_100M_SLOT2_3_DN";
73"CLK_100M_SLOT2_2_DP";
74"CLK_100M_SLOT2_2_DN";
75"CLK_100M_SLOT2_3_DP";
76"CLKBUF1_PLL_MODE";
77"P3V3_9ZX_VDDA_1\g";
78"CLK_100M_SLOT2_0_R_DN";
79"CLK_100M_SLOT2_0_R_DP";
80"CLK_100M_SLOT2_1_R_DP";
81"CLK_100M_SLOT2_0_DP";
82"CLK_100M_SLOT2_0_DN";
83"CLK_100M_SLOT2_1_DP";
84"CLKBUF0_PLL_MODE";
85"P3V3_9ZX_VDDA_0\g";
86"CLK_100M_SLOT1_0_R_DP";
87"CLK_100M_SLOT1_0_R_DN";
88"CLK_100M_SLOT1_1_R_DP";
89"CLK_100M_SLOT1_1_R_DN";
90"CLK_100M_SLOT1_2_R_DP";
91"CLK_100M_SLOT1_3_R_DN";
92"CLK_100M_SLOT1_3_R_DP";
93"CLK_100M_SLOT1_2_R_DN";
94"FM_CLK_100M_SLOT1_1_OE_N";
95"FM_CLK_100M_SLOT1_2_OE_N";
96"FM_CLK_100M_SLOT1_3_OE_N";
97"FM_CLK_100M_SLOT1_0_OE_N";
98"GND\g";
99"CLK_100M_SLOT1_2_DN";
100"CLK_100M_SLOT1_3_DN";
101"CLK_100M_SLOT1_3_DP";
102"CLK_100M_SLOT1_0_DP";
103"CLK_100M_SLOT1_0_DN";
104"CLK_100M_SLOT1_1_DN";
105"CLK_100M_SLOT1_1_DP";
106"CLK_100M_SLOT1_2_DP";
107"GND\g";
108"GND\g";
%"9ZXL0451EKILFT"
"1","(7725,1875)","0","pure_quanta","I225";
;
LOCATION"U69"
$SEC"1"
CDS_SEC"1"
PART_TYPE"SMLF"
MATERIAL"IC"
VALUE"9ZXL0451EKILFT"
PART_NUMBER"AL000451003"
NEEDS_NO_SIZE"TRUE"
CDS_LMAN_SYM_OUTLINE"-475,725,475,-725"
CDS_LIB"pure_quanta";
"VSADR0_TRI"
$PN"5"45;
"NC2"
$PN"17"0;
"NC3"
$PN"30"0;
"VDD0"
$PN"12"48;
"DIF3"
$PN"27"64;
"DIF1"
$PN"19"80;
"EPAD_GND"
$PN"33"22;
"^HIBW_BYPM_LOBW# \B"
$PN"32"76;
"VDD1"
$PN"16"48;
"VDDA"
$PN"31"77;
"NC0"
$PN"10"0;
"DIF3# \B"
$PN"28"65;
"DIF2# \B"
$PN"23"62;
"VOE2# \B"
$PN"24"66;
"DIF2"
$PN"22"63;
"DIF1# \B"
$PN"20"61;
"VOE1# \B"
$PN"18"68;
"DIF0"
$PN"13"79;
"DIF0# \B"
$PN"14"78;
"^CKPWRGD_PD# \B"
$PN"1"41;
"VDD2"
$PN"21"48;
"SMBCLK"
$PN"7"42;
"FBOUT_NC# \B"
$PN"8"0;
"NC1"
$PN"11"0;
"SMBDAT"
$PN"6"43;
"VOE3# \B"
$PN"26"67;
"VOE0# \B"
$PN"15"69;
"FBOUT_NC"
$PN"9"0;
"VDD4"
$PN"29"48;
"VDD3"
$PN"25"48;
"VDDR"
$PN"2"46;
"DIF_IN# \B"
$PN"4"44;
"DIF_IN"
$PN"3"47;
%"9ZXL0451EKILFT"
"1","(7700,5050)","0","pure_quanta","I246";
;
LOCATION"U68"
$SEC"1"
CDS_SEC"1"
PART_TYPE"SMLF"
MATERIAL"IC"
VALUE"9ZXL0451EKILFT"
PART_NUMBER"AL000451003"
NEEDS_NO_SIZE"TRUE"
CDS_LIB"pure_quanta"
CDS_LMAN_SYM_OUTLINE"-475,725,475,-725";
"VSADR0_TRI"
$PN"5"56;
"NC2"
$PN"17"0;
"NC3"
$PN"30"0;
"VDD0"
$PN"12"60;
"DIF3"
$PN"27"92;
"DIF1"
$PN"19"88;
"EPAD_GND"
$PN"33"21;
"^HIBW_BYPM_LOBW# \B"
$PN"32"84;
"VDD1"
$PN"16"60;
"VDDA"
$PN"31"85;
"NC0"
$PN"10"0;
"DIF3# \B"
$PN"28"91;
"DIF2# \B"
$PN"23"93;
"VOE2# \B"
$PN"24"95;
"DIF2"
$PN"22"90;
"DIF1# \B"
$PN"20"89;
"VOE1# \B"
$PN"18"94;
"DIF0"
$PN"13"86;
"DIF0# \B"
$PN"14"87;
"^CKPWRGD_PD# \B"
$PN"1"55;
"VDD2"
$PN"21"60;
"SMBCLK"
$PN"7"53;
"FBOUT_NC# \B"
$PN"8"0;
"NC1"
$PN"11"0;
"SMBDAT"
$PN"6"54;
"VOE3# \B"
$PN"26"96;
"VOE0# \B"
$PN"15"97;
"FBOUT_NC"
$PN"9"0;
"VDD4"
$PN"29"60;
"VDD3"
$PN"25"60;
"VDDR"
$PN"2"57;
"DIF_IN# \B"
$PN"4"58;
"DIF_IN"
$PN"3"59;
%"VCC_CORE"
"1","(6450,5625)","0","mstr_symbols","I313";
;
HDL_POWER"P3V3_9ZX_VDDA_0"
CDS_LIB"mstr_symbols"
BOM_COST"SYS_CLOCK"
VOLTAGE"3.3"
ROOM"DB2000_1_BCLK";
"A"57;
%"VCC_CORE"
"1","(8450,6000)","0","pure_quanta_power","I314";
;
HDL_POWER"P3V3_9ZX_VDDA_0"
CDS_LIB"pure_quanta_power"
BOM_COST"SYS_CLOCK"
VOLTAGE"3.3"
ROOM"DB2000_1_BCLK";
"A"85;
%"UNIVERSAL_POWER"
"1","(6850,6000)","0","mstr_symbols","I315";
;
HDL_POWER"P3V3_9ZX_VDD_0"
CDS_LIB"mstr_symbols"
BOM_COST"SYS_CLOCK"
VOLTAGE"3.3"
ROOM"DB2000_1_BCLK";
"A"60;
%"VCC_CORE"
"1","(8475,2825)","0","pure_quanta_power","I316";
;
HDL_POWER"P3V3_9ZX_VDDA_1"
BOM_COST"SYS_CLOCK"
CDS_LIB"pure_quanta_power"
VOLTAGE"3.3"
ROOM"DB2000_1_BCLK";
"A"77;
%"UNIVERSAL_POWER"
"1","(6875,2825)","0","mstr_symbols","I317";
;
HDL_POWER"P3V3_9ZX_VDD_1"
BOM_COST"SYS_CLOCK"
CDS_LIB"mstr_symbols"
VOLTAGE"3.3"
ROOM"DB2000_1_BCLK";
"A"48;
%"VCC_CORE"
"1","(6475,2450)","0","mstr_symbols","I318";
;
HDL_POWER"P3V3_9ZX_VDDA_1"
BOM_COST"SYS_CLOCK"
CDS_LIB"mstr_symbols"
VOLTAGE"3.3"
ROOM"DB2000_1_BCLK";
"A"46;
%"UNIVERSAL_GND"
"1","(2325,4475)","0","pure_quanta_power","I323";
;
HDL_POWER"GND"
CDS_LIB"pure_quanta_power";
"A"1;
%"Q_CAP"
"1","(2325,4760)","0","pure_quanta","I324";
;
LOCATION"C1193"
$SEC"1"
CDS_SEC"1"
MATERIAL"X6S"
TOLERANCE"10%"
VALUE"1UF"
VOLTAGE"25V"
PACK_TYPE"C0402"
CDS_LIB"pure_quanta"
PART_NUMBER"CH5104KEB02";
"B"
$PN"2"1;
"A"
$PN"1"32;
%"UNIVERSAL_GND"
"1","(2725,4450)","0","pure_quanta_power","I326";
;
HDL_POWER"GND"
CDS_LIB"pure_quanta_power";
"A"2;
%"UNIVERSAL_GND"
"1","(2975,4450)","0","pure_quanta_power","I327";
;
HDL_POWER"GND"
CDS_LIB"pure_quanta_power";
"A"3;
%"Q_CAP"
"1","(2725,4725)","0","pure_quanta","I328";
;
LOCATION"C1197"
$SEC"1"
CDS_SEC"1"
MATERIAL"X7R"
TOLERANCE"10%"
VALUE"0.1UF"
VOLTAGE"25V"
PACK_TYPE"0402"
CDS_LIB"pure_quanta"
PART_NUMBER"CH4104K1B00";
"B"
$PN"2"2;
"A"
$PN"1"32;
%"Q_CAP"
"1","(2975,4725)","0","pure_quanta","I330";
;
LOCATION"C1202"
$SEC"1"
CDS_SEC"1"
MATERIAL"X7R"
TOLERANCE"10%"
VALUE"0.1UF"
VOLTAGE"25V"
PACK_TYPE"0402"
CDS_LIB"pure_quanta"
PART_NUMBER"CH4104K1B00";
"B"
$PN"2"3;
"A"
$PN"1"32;
%"UNIVERSAL_GND"
"1","(3200,4450)","0","pure_quanta_power","I332";
;
HDL_POWER"GND"
CDS_LIB"pure_quanta_power";
"A"4;
%"UNIVERSAL_GND"
"1","(3430,4445)","0","pure_quanta_power","I333";
;
HDL_POWER"GND"
CDS_LIB"pure_quanta_power";
"A"5;
%"Q_CAP"
"1","(3200,4725)","0","pure_quanta","I334";
;
LOCATION"C1206"
$SEC"1"
CDS_SEC"1"
MATERIAL"X7R"
TOLERANCE"10%"
VALUE"0.1UF"
VOLTAGE"25V"
PACK_TYPE"0402"
CDS_LIB"pure_quanta"
PART_NUMBER"CH4104K1B00";
"B"
$PN"2"4;
"A"
$PN"1"32;
%"Q_CAP"
"1","(3430,4720)","0","pure_quanta","I336";
;
LOCATION"C1209"
$SEC"1"
CDS_SEC"1"
MATERIAL"X7R"
TOLERANCE"10%"
VALUE"0.1UF"
VOLTAGE"25V"
PACK_TYPE"0402"
CDS_LIB"pure_quanta"
PART_NUMBER"CH4104K1B00";
"B"
$PN"2"5;
"A"
$PN"1"32;
%"Q_INDUCTOR"
"1","(2150,5425)","0","pure_quanta","I337";
;
LOCATION"L6"
$SEC"1"
CDS_SEC"1"
MATERIAL"IND"
VALUE"330/2.5A"
PART_NUMBER"CX12S331000"
PACK_TYPE"SMLF"
NEEDS_NO_SIZE"TRUE"
CDS_LIB"pure_quanta";
"1"
$PN"1"31;
"2"
$PN"2"32;
%"UNIVERSAL_POWER"
"1","(1800,5550)","0","pure_quanta_power","I338";
;
HDL_POWER"P3V3"
CDS_LIB"pure_quanta_power";
"A"31;
%"UNIVERSAL_POWER"
"1","(3475,5600)","0","pure_quanta_power","I343";
;
HDL_POWER"P3V3_9ZX_VDD_0"
CDS_LIB"pure_quanta_power"
BOM_COST"SYS_CLOCK"
VOLTAGE"3.3"
ROOM"DB2000_1_BCLK";
"A"32;
%"UNIVERSAL_GND"
"1","(3660,4440)","0","pure_quanta_power","I344";
;
HDL_POWER"GND"
CDS_LIB"pure_quanta_power";
"A"6;
%"Q_CAP"
"1","(3660,4715)","0","pure_quanta","I346";
;
LOCATION"C1211"
$SEC"1"
CDS_SEC"1"
MATERIAL"X7R"
TOLERANCE"10%"
VALUE"0.1UF"
VOLTAGE"25V"
PACK_TYPE"0402"
CDS_LIB"pure_quanta"
PART_NUMBER"CH4104K1B00";
"B"
$PN"2"6;
"A"
$PN"1"32;
%"UNIVERSAL_GND"
"1","(4225,4975)","0","pure_quanta_power","I348";
;
HDL_POWER"GND"
CDS_LIB"pure_quanta_power";
"A"7;
%"UNIVERSAL_GND"
"1","(4475,4975)","0","pure_quanta_power","I349";
;
HDL_POWER"GND"
CDS_LIB"pure_quanta_power";
"A"8;
%"UNIVERSAL_GND"
"1","(4675,4975)","0","pure_quanta_power","I350";
;
HDL_POWER"GND"
CDS_LIB"pure_quanta_power";
"A"9;
%"Q_RES"
"1","(3825,5400)","0","pure_quanta","I351";
;
LOCATION"R794"
$SEC"1"
CDS_SEC"1"
WATTAGE"1/10W"
MATERIAL"CHIP"
TOLERANCE"1%"
VALUE"1"
PACK_TYPE"0603LF"
CDS_LIB"pure_quanta"
PART_NUMBER"CS-1003F920";
"B"
$PN"2"49;
"A"
$PN"1"32;
%"Q_CAP"
"1","(4225,5250)","0","pure_quanta","I352";
;
LOCATION"C1215"
$SEC"1"
CDS_SEC"1"
MATERIAL"X6S"
TOLERANCE"10%"
VALUE"1UF"
VOLTAGE"25V"
PACK_TYPE"C0402"
CDS_LIB"pure_quanta"
PART_NUMBER"CH5104KEB02";
"B"
$PN"2"7;
"A"
$PN"1"49;
%"Q_CAP"
"1","(4475,5250)","0","pure_quanta","I353";
;
LOCATION"C1217"
$SEC"1"
CDS_SEC"1"
MATERIAL"X7R"
TOLERANCE"10%"
VALUE"0.1UF"
VOLTAGE"25V"
PACK_TYPE"0402"
CDS_LIB"pure_quanta"
PART_NUMBER"CH4104K1B00";
"B"
$PN"2"8;
"A"
$PN"1"49;
%"Q_CAP"
"1","(4675,5250)","0","pure_quanta","I354";
;
LOCATION"C1219"
$SEC"1"
CDS_SEC"1"
MATERIAL"X7R"
TOLERANCE"10%"
VALUE"0.1UF"
VOLTAGE"25V"
PACK_TYPE"0402"
CDS_LIB"pure_quanta"
PART_NUMBER"CH4104K1B00";
"B"
$PN"2"9;
"A"
$PN"1"49;
%"VCC_CORE"
"1","(4675,5600)","0","pure_quanta_power","I355";
;
HDL_POWER"P3V3_9ZX_VDDA_0"
BOM_COST"SYS_CLOCK"
CDS_LIB"pure_quanta_power"
VOLTAGE"3.3"
ROOM"DB2000_1_BCLK";
"A"49;
%"UNIVERSAL_GND"
"1","(2325,950)","0","pure_quanta_power","I356";
;
HDL_POWER"GND"
CDS_LIB"pure_quanta_power";
"A"10;
%"Q_CAP"
"1","(2325,1235)","0","pure_quanta","I357";
;
LOCATION"C1194"
$SEC"1"
CDS_SEC"1"
MATERIAL"X6S"
TOLERANCE"10%"
VALUE"1UF"
VOLTAGE"25V"
PACK_TYPE"C0402"
CDS_LIB"pure_quanta"
PART_NUMBER"CH5104KEB02";
"B"
$PN"2"10;
"A"
$PN"1"28;
%"UNIVERSAL_GND"
"1","(2725,925)","0","pure_quanta_power","I359";
;
HDL_POWER"GND"
CDS_LIB"pure_quanta_power";
"A"11;
%"UNIVERSAL_GND"
"1","(2975,925)","0","pure_quanta_power","I360";
;
HDL_POWER"GND"
CDS_LIB"pure_quanta_power";
"A"12;
%"Q_CAP"
"1","(2725,1200)","0","pure_quanta","I361";
;
LOCATION"C1200"
$SEC"1"
CDS_SEC"1"
MATERIAL"X7R"
TOLERANCE"10%"
VALUE"0.1UF"
VOLTAGE"25V"
PACK_TYPE"0402"
CDS_LIB"pure_quanta"
PART_NUMBER"CH4104K1B00";
"B"
$PN"2"11;
"A"
$PN"1"28;
%"Q_CAP"
"1","(2975,1200)","0","pure_quanta","I363";
;
LOCATION"C1204"
$SEC"1"
CDS_SEC"1"
MATERIAL"X7R"
TOLERANCE"10%"
VALUE"0.1UF"
VOLTAGE"25V"
PACK_TYPE"0402"
CDS_LIB"pure_quanta"
PART_NUMBER"CH4104K1B00";
"B"
$PN"2"12;
"A"
$PN"1"28;
%"UNIVERSAL_GND"
"1","(3200,925)","0","pure_quanta_power","I365";
;
HDL_POWER"GND"
CDS_LIB"pure_quanta_power";
"A"13;
%"UNIVERSAL_GND"
"1","(3430,920)","0","pure_quanta_power","I366";
;
HDL_POWER"GND"
CDS_LIB"pure_quanta_power";
"A"14;
%"Q_CAP"
"1","(3200,1200)","0","pure_quanta","I367";
;
LOCATION"C1208"
$SEC"1"
CDS_SEC"1"
MATERIAL"X7R"
TOLERANCE"10%"
VALUE"0.1UF"
VOLTAGE"25V"
PACK_TYPE"0402"
CDS_LIB"pure_quanta"
PART_NUMBER"CH4104K1B00";
"B"
$PN"2"13;
"A"
$PN"1"28;
%"Q_CAP"
"1","(3430,1195)","0","pure_quanta","I369";
;
LOCATION"C1210"
$SEC"1"
CDS_SEC"1"
MATERIAL"X7R"
TOLERANCE"10%"
VALUE"0.1UF"
VOLTAGE"25V"
PACK_TYPE"0402"
CDS_LIB"pure_quanta"
PART_NUMBER"CH4104K1B00";
"B"
$PN"2"14;
"A"
$PN"1"28;
%"Q_INDUCTOR"
"1","(2150,1900)","0","pure_quanta","I370";
;
LOCATION"L7"
$SEC"1"
CDS_SEC"1"
MATERIAL"IND"
VALUE"330/2.5A"
PART_NUMBER"CX12S331000"
PACK_TYPE"SMLF"
NEEDS_NO_SIZE"TRUE"
CDS_LIB"pure_quanta";
"1"
$PN"1"27;
"2"
$PN"2"28;
%"UNIVERSAL_POWER"
"1","(1800,2025)","0","pure_quanta_power","I371";
;
HDL_POWER"P3V3"
CDS_LIB"pure_quanta_power";
"A"27;
%"UNIVERSAL_POWER"
"1","(3475,2075)","0","pure_quanta_power","I376";
;
HDL_POWER"P3V3_9ZX_VDD_1"
CDS_LIB"pure_quanta_power"
BOM_COST"SYS_CLOCK"
VOLTAGE"3.3"
ROOM"DB2000_1_BCLK";
"A"28;
%"UNIVERSAL_GND"
"1","(3660,915)","0","pure_quanta_power","I377";
;
HDL_POWER"GND"
CDS_LIB"pure_quanta_power";
"A"15;
%"Q_CAP"
"1","(3660,1190)","0","pure_quanta","I379";
;
LOCATION"C1212"
$SEC"1"
CDS_SEC"1"
MATERIAL"X7R"
TOLERANCE"10%"
VALUE"0.1UF"
VOLTAGE"25V"
PACK_TYPE"0402"
CDS_LIB"pure_quanta"
PART_NUMBER"CH4104K1B00";
"B"
$PN"2"15;
"A"
$PN"1"28;
%"UNIVERSAL_GND"
"1","(4275,1450)","0","pure_quanta_power","I381";
;
HDL_POWER"GND"
CDS_LIB"pure_quanta_power";
"A"16;
%"UNIVERSAL_GND"
"1","(4525,1450)","0","pure_quanta_power","I382";
;
HDL_POWER"GND"
CDS_LIB"pure_quanta_power";
"A"17;
%"UNIVERSAL_GND"
"1","(4725,1450)","0","pure_quanta_power","I383";
;
HDL_POWER"GND"
CDS_LIB"pure_quanta_power";
"A"18;
%"Q_RES"
"1","(3825,1875)","0","pure_quanta","I384";
;
LOCATION"R795"
$SEC"1"
CDS_SEC"1"
WATTAGE"1/10W"
MATERIAL"CHIP"
TOLERANCE"1%"
VALUE"1"
PACK_TYPE"0603LF"
CDS_LIB"pure_quanta"
PART_NUMBER"CS-1003F920";
"B"
$PN"2"33;
"A"
$PN"1"28;
%"Q_CAP"
"1","(4275,1725)","0","pure_quanta","I385";
;
LOCATION"C1216"
$SEC"1"
CDS_SEC"1"
MATERIAL"X6S"
TOLERANCE"10%"
VALUE"1UF"
VOLTAGE"25V"
PACK_TYPE"C0402"
CDS_LIB"pure_quanta"
PART_NUMBER"CH5104KEB02";
"B"
$PN"2"16;
"A"
$PN"1"33;
%"Q_CAP"
"1","(4525,1725)","0","pure_quanta","I386";
;
LOCATION"C1218"
$SEC"1"
CDS_SEC"1"
MATERIAL"X7R"
TOLERANCE"10%"
VALUE"0.1UF"
VOLTAGE"25V"
PACK_TYPE"0402"
CDS_LIB"pure_quanta"
PART_NUMBER"CH4104K1B00";
"B"
$PN"2"17;
"A"
$PN"1"33;
%"Q_CAP"
"1","(4725,1725)","0","pure_quanta","I387";
;
LOCATION"C1220"
$SEC"1"
CDS_SEC"1"
MATERIAL"X7R"
TOLERANCE"10%"
VALUE"0.1UF"
VOLTAGE"25V"
PACK_TYPE"0402"
CDS_LIB"pure_quanta"
PART_NUMBER"CH4104K1B00";
"B"
$PN"2"18;
"A"
$PN"1"33;
%"VCC_CORE"
"1","(4725,2075)","0","pure_quanta_power","I388";
;
HDL_POWER"P3V3_9ZX_VDDA_1"
BOM_COST"SYS_CLOCK"
CDS_LIB"pure_quanta_power"
VOLTAGE"3.3"
ROOM"DB2000_1_BCLK";
"A"33;
%"Q_RES"
"1","(9450,5325)","0","pure_quanta","I399";
;
LOCATION"R2288"
$SEC"1"
CDS_SEC"1"
VALUE"0"
CDS_LIB"pure_quanta"
WATTAGE"1/16W"
MATERIAL"CHIP"
TOLERANCE"5%"
PART_NUMBER"CS00002JB38"
PACK_TYPE"0402LF";
"B"
$PN"2"102;
"A"
$PN"1"86;
%"Q_RES"
"1","(9450,5275)","0","pure_quanta","I400";
;
LOCATION"R2289"
$SEC"1"
CDS_SEC"1"
VALUE"0"
CDS_LIB"pure_quanta"
WATTAGE"1/16W"
MATERIAL"CHIP"
TOLERANCE"5%"
PART_NUMBER"CS00002JB38"
PACK_TYPE"0402LF";
"B"
$PN"2"103;
"A"
$PN"1"87;
%"Q_RES"
"1","(9450,5225)","0","pure_quanta","I405";
;
LOCATION"R2290"
$SEC"1"
CDS_SEC"1"
VALUE"0"
CDS_LIB"pure_quanta"
WATTAGE"1/16W"
MATERIAL"CHIP"
TOLERANCE"5%"
PART_NUMBER"CS00002JB38"
PACK_TYPE"0402LF";
"B"
$PN"2"105;
"A"
$PN"1"88;
%"Q_RES"
"1","(9450,5175)","0","pure_quanta","I406";
;
LOCATION"R2291"
$SEC"1"
CDS_SEC"1"
VALUE"0"
CDS_LIB"pure_quanta"
WATTAGE"1/16W"
MATERIAL"CHIP"
TOLERANCE"5%"
PART_NUMBER"CS00002JB38"
PACK_TYPE"0402LF";
"B"
$PN"2"104;
"A"
$PN"1"89;
%"Q_RES"
"1","(9300,2000)","0","pure_quanta","I411";
;
LOCATION"R2287"
$SEC"1"
CDS_SEC"1"
VALUE"0"
CDS_LIB"pure_quanta"
WATTAGE"1/16W"
MATERIAL"CHIP"
TOLERANCE"5%"
PART_NUMBER"CS00002JB38"
PACK_TYPE"0402LF";
"B"
$PN"2"71;
"A"
$PN"1"61;
%"Q_RES"
"1","(9300,2150)","0","pure_quanta","I412";
;
LOCATION"R2284"
$SEC"1"
CDS_SEC"1"
VALUE"0"
CDS_LIB"pure_quanta"
WATTAGE"1/16W"
MATERIAL"CHIP"
TOLERANCE"5%"
PART_NUMBER"CS00002JB38"
PACK_TYPE"0402LF";
"B"
$PN"2"81;
"A"
$PN"1"79;
%"Q_RES"
"1","(9300,2100)","0","pure_quanta","I413";
;
LOCATION"R2285"
$SEC"1"
CDS_SEC"1"
VALUE"0"
CDS_LIB"pure_quanta"
WATTAGE"1/16W"
MATERIAL"CHIP"
TOLERANCE"5%"
PART_NUMBER"CS00002JB38"
PACK_TYPE"0402LF";
"B"
$PN"2"82;
"A"
$PN"1"78;
%"Q_RES"
"1","(9300,2050)","0","pure_quanta","I414";
;
LOCATION"R2286"
$SEC"1"
CDS_SEC"1"
VALUE"0"
CDS_LIB"pure_quanta"
WATTAGE"1/16W"
MATERIAL"CHIP"
TOLERANCE"5%"
PART_NUMBER"CS00002JB38"
PACK_TYPE"0402LF";
"B"
$PN"2"83;
"A"
$PN"1"80;
%"UNIVERSAL_POWER"
"1","(9275,3000)","0","pure_quanta_power","I419";
;
HDL_POWER"P3V3"
CDS_LIB"pure_quanta_power";
"A"19;
%"Q_RES"
"2","(9275,2800)","0","pure_quanta","I420";
;
LOCATION"R119"
$SEC"1"
CDS_SEC"1"
WATTAGE"1/16W"
MATERIAL"CHIP"
TOLERANCE"5%"
VALUE"10K"
PACK_TYPE"0402LF"
CDS_LIB"pure_quanta"
PART_NUMBER"TMP_QCS31002JB28";
"A"
$PN"1"19;
"B"
$PN"2"76;
%"Q_RES"
"2","(9275,2450)","0","pure_quanta","I421";
;
LOCATION"R120"
$SEC"1"
CDS_SEC"1"
WATTAGE"1/16W"
MATERIAL"CHIP"
TOLERANCE"5%"
VALUE"10K"
PACK_TYPE"0402LF"
CDS_LIB"pure_quanta"
PART_NUMBER"TMP_QCS31002JB28";
"A"
$PN"1"76;
"B"
$PN"2"108;
%"UNIVERSAL_GND"
"1","(9275,2300)","0","pure_quanta_power","I422";
;
HDL_POWER"GND"
CDS_LIB"pure_quanta_power";
"A"108;
%"Q_RES"
"2","(9200,5950)","0","pure_quanta","I423";
;
LOCATION"R117"
$SEC"1"
CDS_SEC"1"
WATTAGE"1/16W"
MATERIAL"CHIP"
TOLERANCE"5%"
VALUE"10K"
PACK_TYPE"0402LF"
CDS_LIB"pure_quanta"
PART_NUMBER"TMP_QCS31002JB28";
"A"
$PN"1"20;
"B"
$PN"2"84;
%"Q_RES"
"2","(9200,5600)","0","pure_quanta","I424";
;
LOCATION"R118"
$SEC"1"
CDS_SEC"1"
WATTAGE"1/16W"
MATERIAL"CHIP"
TOLERANCE"5%"
VALUE"10K"
PACK_TYPE"0402LF"
CDS_LIB"pure_quanta"
PART_NUMBER"TMP_QCS31002JB28";
"A"
$PN"1"84;
"B"
$PN"2"107;
%"UNIVERSAL_POWER"
"1","(9200,6150)","0","pure_quanta_power","I425";
;
HDL_POWER"P3V3"
CDS_LIB"pure_quanta_power";
"A"20;
%"UNIVERSAL_GND"
"1","(9200,5450)","0","pure_quanta_power","I426";
;
HDL_POWER"GND"
CDS_LIB"pure_quanta_power";
"A"107;
%"UNIVERSAL_GND"
"1","(8400,4275)","0","pure_quanta_power","I427";
;
HDL_POWER"GND"
CDS_LIB"pure_quanta_power";
"A"21;
%"UNIVERSAL_GND"
"1","(8425,1100)","0","pure_quanta_power","I428";
;
HDL_POWER"GND"
CDS_LIB"pure_quanta_power";
"A"22;
%"UNIVERSAL_POWER"
"1","(2825,3875)","0","pure_quanta_power","I429";
;
HDL_POWER"P3V3"
CDS_LIB"pure_quanta_power";
"A"23;
%"UNIVERSAL_GND"
"1","(2825,3025)","0","pure_quanta_power","I432";
;
CDS_LIB"pure_quanta_power"
HDL_POWER"GND";
"A"24;
%"Q_RES"
"2","(2825,3200)","0","pure_quanta","I433";
;
LOCATION"R592"
$SEC"1"
CDS_SEC"1"
WATTAGE"1/16W"
MATERIAL"CHIP"
TOLERANCE"5%"
VALUE"1K"
PACK_TYPE"0402LF"
CDS_LIB"pure_quanta"
PART_NUMBER"TMP_QCS21002JB34";
"A"
$PN"1"29;
"B"
$PN"2"24;
%"Q_RES"
"2","(2825,3625)","0","pure_quanta","I434";
;
LOCATION"R591"
$SEC"1"
CDS_SEC"1"
WATTAGE"1/16W"
MATERIAL"EMPTY"
TOLERANCE"5%"
VALUE"1K"
PACK_TYPE"0402LF"
CDS_LIB"pure_quanta"
PART_NUMBER"TMP_QCS21002JB34";
"A"
$PN"1"23;
"B"
$PN"2"29;
%"UNIVERSAL_POWER"
"1","(3050,3875)","0","pure_quanta_power","I435";
;
HDL_POWER"P3V3"
CDS_LIB"pure_quanta_power";
"A"25;
%"UNIVERSAL_GND"
"1","(3050,3025)","0","pure_quanta_power","I437";
;
CDS_LIB"pure_quanta_power"
HDL_POWER"GND";
"A"26;
%"Q_RES"
"2","(3050,3200)","0","pure_quanta","I438";
;
LOCATION"R594"
$SEC"1"
CDS_SEC"1"
WATTAGE"1/16W"
MATERIAL"CHIP"
TOLERANCE"5%"
VALUE"1K"
PACK_TYPE"0402LF"
CDS_LIB"pure_quanta"
PART_NUMBER"TMP_QCS21002JB34";
"A"
$PN"1"30;
"B"
$PN"2"26;
%"Q_RES"
"1","(9450,4975)","0","pure_quanta","I441";
;
LOCATION"R151"
$SEC"1"
CDS_SEC"1"
VALUE"0"
CDS_LIB"pure_quanta"
WATTAGE"1/16W"
MATERIAL"CHIP"
TOLERANCE"5%"
PART_NUMBER"CS00002JB38"
PACK_TYPE"0402LF";
"B"
$PN"2"100;
"A"
$PN"1"91;
%"Q_RES"
"1","(9450,5025)","0","pure_quanta","I442";
;
LOCATION"R150"
$SEC"1"
CDS_SEC"1"
VALUE"0"
CDS_LIB"pure_quanta"
WATTAGE"1/16W"
MATERIAL"CHIP"
TOLERANCE"5%"
PART_NUMBER"CS00002JB38"
PACK_TYPE"0402LF";
"B"
$PN"2"101;
"A"
$PN"1"92;
%"Q_RES"
"1","(9450,5075)","0","pure_quanta","I443";
;
LOCATION"R149"
$SEC"1"
CDS_SEC"1"
VALUE"0"
CDS_LIB"pure_quanta"
WATTAGE"1/16W"
MATERIAL"CHIP"
TOLERANCE"5%"
PART_NUMBER"CS00002JB38"
PACK_TYPE"0402LF";
"B"
$PN"2"99;
"A"
$PN"1"93;
%"Q_RES"
"1","(9450,5125)","0","pure_quanta","I444";
;
LOCATION"R69"
$SEC"1"
CDS_SEC"1"
VALUE"0"
CDS_LIB"pure_quanta"
WATTAGE"1/16W"
MATERIAL"CHIP"
TOLERANCE"5%"
PART_NUMBER"CS00002JB38"
PACK_TYPE"0402LF";
"B"
$PN"2"106;
"A"
$PN"1"90;
%"Q_RES"
"1","(9300,1800)","0","pure_quanta","I449";
;
LOCATION"R68"
$SEC"1"
CDS_SEC"1"
VALUE"0"
CDS_LIB"pure_quanta"
WATTAGE"1/16W"
MATERIAL"CHIP"
TOLERANCE"5%"
PART_NUMBER"CS00002JB38"
PACK_TYPE"0402LF";
"B"
$PN"2"72;
"A"
$PN"1"65;
%"Q_RES"
"1","(9300,1850)","0","pure_quanta","I450";
;
LOCATION"R67"
$SEC"1"
CDS_SEC"1"
VALUE"0"
CDS_LIB"pure_quanta"
WATTAGE"1/16W"
MATERIAL"CHIP"
TOLERANCE"5%"
PART_NUMBER"CS00002JB38"
PACK_TYPE"0402LF";
"B"
$PN"2"75;
"A"
$PN"1"64;
%"Q_RES"
"1","(9300,1900)","0","pure_quanta","I451";
;
LOCATION"R66"
$SEC"1"
CDS_SEC"1"
VALUE"0"
CDS_LIB"pure_quanta"
WATTAGE"1/16W"
MATERIAL"CHIP"
TOLERANCE"5%"
PART_NUMBER"CS00002JB38"
PACK_TYPE"0402LF";
"B"
$PN"2"74;
"A"
$PN"1"62;
%"Q_RES"
"1","(9300,1950)","0","pure_quanta","I452";
;
LOCATION"R65"
$SEC"1"
CDS_SEC"1"
VALUE"0"
CDS_LIB"pure_quanta"
WATTAGE"1/16W"
MATERIAL"CHIP"
TOLERANCE"5%"
PART_NUMBER"CS00002JB38"
PACK_TYPE"0402LF";
"B"
$PN"2"73;
"A"
$PN"1"63;
%"Q_RES"
"1","(6225,4925)","0","pure_quanta","I458";
;
LOCATION"R593"
$SEC"1"
CDS_SEC"1"
VALUE"0"
CDS_LIB"pure_quanta"
WATTAGE"1/16W"
MATERIAL"CHIP"
TOLERANCE"5%"
PART_NUMBER"CS00002JB38"
PACK_TYPE"0402LF";
"B"
$PN"2"53;
"A"
$PN"1"50;
%"Q_RES"
"1","(6225,4975)","0","pure_quanta","I459";
;
LOCATION"R290"
$SEC"1"
CDS_SEC"1"
VALUE"0"
CDS_LIB"pure_quanta"
WATTAGE"1/16W"
MATERIAL"CHIP"
TOLERANCE"5%"
PART_NUMBER"CS00002JB38"
PACK_TYPE"0402LF";
"B"
$PN"2"54;
"A"
$PN"1"51;
%"Q_RES"
"2","(3050,3625)","0","pure_quanta","I466";
;
LOCATION"R281"
$SEC"1"
CDS_SEC"1"
WATTAGE"1/16W"
MATERIAL"CHIP"
TOLERANCE"5%"
VALUE"1K"
PACK_TYPE"0402LF"
CDS_LIB"pure_quanta"
PART_NUMBER"TMP_QCS21002JB34";
"A"
$PN"1"25;
"B"
$PN"2"30;
%"Q_RES"
"1","(6250,1800)","0","pure_quanta","I469";
;
LOCATION"R597"
$SEC"1"
CDS_SEC"1"
VALUE"0"
CDS_LIB"pure_quanta"
WATTAGE"1/16W"
MATERIAL"CHIP"
TOLERANCE"5%"
PART_NUMBER"CS00002JB38"
PACK_TYPE"0402LF";
"B"
$PN"2"43;
"A"
$PN"1"39;
%"Q_RES"
"1","(6250,1750)","0","pure_quanta","I470";
;
LOCATION"R624"
$SEC"1"
CDS_SEC"1"
VALUE"0"
CDS_LIB"pure_quanta"
WATTAGE"1/16W"
MATERIAL"CHIP"
TOLERANCE"5%"
PART_NUMBER"CS00002JB38"
PACK_TYPE"0402LF";
"B"
$PN"2"42;
"A"
$PN"1"38;
%"Q_RES"
"1","(6225,4825)","0","pure_quanta","I473";
;
LOCATION"R1212"
$SEC"1"
CDS_SEC"1"
VALUE"0"
CDS_LIB"pure_quanta"
WATTAGE"1/16W"
MATERIAL"CHIP"
TOLERANCE"5%"
PART_NUMBER"CS00002JB38"
PACK_TYPE"0402LF";
"B"
$PN"2"55;
"A"
$PN"1"52;
%"Q_RES"
"1","(6250,1650)","0","pure_quanta","I475";
;
LOCATION"R1213"
$SEC"1"
CDS_SEC"1"
VALUE"0"
CDS_LIB"pure_quanta"
WATTAGE"1/16W"
MATERIAL"CHIP"
TOLERANCE"5%"
PART_NUMBER"CS00002JB38"
PACK_TYPE"0402LF";
"B"
$PN"2"41;
"A"
$PN"1"40;
%"Q_RES"
"2","(4550,3675)","0","pure_quanta","I477";
;
LOCATION"R949"
$SEC"1"
CDS_SEC"1"
WATTAGE"1/16W"
MATERIAL"EMPTY"
TOLERANCE"1%"
VALUE"4.7K"
PACK_TYPE"0402LF"
CDS_LIB"pure_quanta"
PART_NUMBER"CS24702FB10";
"A"
$PN"1"35;
"B"
$PN"2"37;
%"Q_RES"
"2","(4550,3275)","0","pure_quanta","I478";
;
LOCATION"R1209"
$SEC"1"
CDS_SEC"1"
WATTAGE"1/16W"
MATERIAL"EMPTY"
TOLERANCE"1%"
VALUE"4.7K"
PACK_TYPE"0402LF"
CDS_LIB"pure_quanta"
PART_NUMBER"CS24702FB10";
"A"
$PN"1"37;
"B"
$PN"2"34;
%"UNIVERSAL_POWER"
"1","(4550,3925)","0","pure_quanta_power","I479";
;
HDL_POWER"P3V3"
CDS_LIB"pure_quanta_power";
"A"35;
%"UNIVERSAL_GND"
"1","(4550,3025)","0","pure_quanta_power","I480";
;
CDS_LIB"pure_quanta_power"
HDL_POWER"GND";
"A"34;
%"Q_RES"
"2","(4800,3675)","0","pure_quanta","I481";
;
LOCATION"R1210"
$SEC"1"
CDS_SEC"1"
WATTAGE"1/16W"
MATERIAL"EMPTY"
TOLERANCE"1%"
VALUE"4.7K"
PACK_TYPE"0402LF"
CDS_LIB"pure_quanta"
PART_NUMBER"CS24702FB10";
"A"
$PN"1"35;
"B"
$PN"2"36;
%"Q_RES"
"2","(4800,3275)","0","pure_quanta","I482";
;
LOCATION"R1211"
$SEC"1"
CDS_SEC"1"
WATTAGE"1/16W"
MATERIAL"EMPTY"
TOLERANCE"1%"
VALUE"4.7K"
PACK_TYPE"0402LF"
CDS_LIB"pure_quanta"
PART_NUMBER"CS24702FB10";
"A"
$PN"1"36;
"B"
$PN"2"34;
%"UNIVERSAL_GND"
"1","(9675,4025)","0","pure_quanta_power","I497";
;
HDL_POWER"GND"
CDS_LIB"pure_quanta_power";
"A"98;
%"UNIVERSAL_GND"
"1","(9575,875)","0","pure_quanta_power","I504";
;
HDL_POWER"GND"
CDS_LIB"pure_quanta_power";
"A"70;
%"Q_RES"
"1","(9350,1250)","0","pure_quanta","I510";
;
LOCATION"R1218"
$SEC"1"
CDS_SEC"1"
MATERIAL"EMPTY"
VALUE"100"
CDS_LIB"pure_quanta"
WATTAGE"1/16W"
TOLERANCE"1%"
PART_NUMBER"TMP_QCS11002FB22"
PACK_TYPE"0402LF";
"B"
$PN"2"70;
"A"
$PN"1"69;
%"Q_RES"
"1","(9350,1150)","0","pure_quanta","I511";
;
LOCATION"R1219"
$SEC"1"
CDS_SEC"1"
MATERIAL"EMPTY"
VALUE"100"
CDS_LIB"pure_quanta"
WATTAGE"1/16W"
TOLERANCE"1%"
PART_NUMBER"TMP_QCS11002FB22"
PACK_TYPE"0402LF";
"B"
$PN"2"70;
"A"
$PN"1"68;
%"Q_RES"
"1","(9350,1075)","0","pure_quanta","I512";
;
LOCATION"R1220"
$SEC"1"
CDS_SEC"1"
MATERIAL"EMPTY"
VALUE"100"
CDS_LIB"pure_quanta"
WATTAGE"1/16W"
TOLERANCE"1%"
PART_NUMBER"TMP_QCS11002FB22"
PACK_TYPE"0402LF";
"B"
$PN"2"70;
"A"
$PN"1"66;
%"Q_RES"
"1","(9350,975)","0","pure_quanta","I513";
;
LOCATION"R1221"
$SEC"1"
CDS_SEC"1"
MATERIAL"EMPTY"
VALUE"100"
CDS_LIB"pure_quanta"
WATTAGE"1/16W"
TOLERANCE"1%"
PART_NUMBER"TMP_QCS11002FB22"
PACK_TYPE"0402LF";
"B"
$PN"2"70;
"A"
$PN"1"67;
%"Q_RES"
"1","(9450,4500)","0","pure_quanta","I514";
;
LOCATION"R1225"
$SEC"1"
CDS_SEC"1"
MATERIAL"EMPTY"
VALUE"100"
CDS_LIB"pure_quanta"
WATTAGE"1/16W"
TOLERANCE"1%"
PART_NUMBER"TMP_QCS11002FB22"
PACK_TYPE"0402LF";
"B"
$PN"2"98;
"A"
$PN"1"94;
%"Q_RES"
"1","(9450,4400)","0","pure_quanta","I515";
;
LOCATION"R1226"
$SEC"1"
CDS_SEC"1"
MATERIAL"EMPTY"
VALUE"100"
CDS_LIB"pure_quanta"
WATTAGE"1/16W"
TOLERANCE"1%"
PART_NUMBER"TMP_QCS11002FB22"
PACK_TYPE"0402LF";
"B"
$PN"2"98;
"A"
$PN"1"95;
%"Q_RES"
"1","(9450,4300)","0","pure_quanta","I516";
;
LOCATION"R1227"
$SEC"1"
CDS_SEC"1"
MATERIAL"EMPTY"
VALUE"100"
CDS_LIB"pure_quanta"
WATTAGE"1/16W"
TOLERANCE"1%"
PART_NUMBER"TMP_QCS11002FB22"
PACK_TYPE"0402LF";
"B"
$PN"2"98;
"A"
$PN"1"96;
END.
